(kicad_pcb
	(version 20260206)
	(generator "pcbnew")
	(generator_version "10.0")
	(general
		(thickness 1.6)
		(legacy_teardrops no)
	)
	(paper "A4")
	(title_block
		(title "Bryce Canyon_F.DPB_16315-1-OCP.brd")
		(comment 1 "Bryce Canyon / footprint 2079 of 2223 (IO1), pads 1-67 of 202")
	)
	(layers
		(0 "F.Cu" signal "TOP")
		(4 "In1.Cu" signal "L2GND")
		(6 "In2.Cu" signal "L3")
		(8 "In3.Cu" signal "L4GND")
		(10 "In4.Cu" signal "L5")
		(12 "In5.Cu" signal "L6VCC")
		(14 "In6.Cu" signal "L7VCC")
		(16 "In7.Cu" signal "L8")
		(18 "In8.Cu" signal "L9GND")
		(20 "In9.Cu" signal "L10")
		(22 "In10.Cu" signal "L11GND")
		(2 "B.Cu" signal "BOTTOM")
		(9 "F.Adhes" user "F.Adhesive")
		(11 "B.Adhes" user "B.Adhesive")
		(13 "F.Paste" user "Package Geometry/Pastemask Top")
		(15 "B.Paste" user "Package Geometry/Pastemask Bottom")
		(5 "F.SilkS" user "Ref Des/Silkscreen Top")
		(7 "B.SilkS" user "Ref Des/Silkscreen Bottom")
		(1 "F.Mask" user "Board Geometry/Soldermask Top")
		(3 "B.Mask" user "Board Geometry/Soldermask Bottom")
		(17 "Dwgs.User" user "User.Drawings")
		(19 "Cmts.User" user "User.Comments")
		(21 "Eco1.User" user "User.Eco1")
		(23 "Eco2.User" user "User.Eco2")
		(25 "Edge.Cuts" user "Board Geometry/Outline")
		(27 "Margin" user)
		(31 "F.CrtYd" user "Package Geometry/Place Bound Top")
		(29 "B.CrtYd" user "Package Geometry/Place Bound Bottom")
		(35 "F.Fab" user "Ref Des/Assembly Top")
		(33 "B.Fab" user "Ref Des/Assembly Bottom")
	)
	(footprint ""
		(layer "B.Cu")
		(at 143.34998 -30.550104 180)
		(property "Reference" "IO1"
			(at 0 0 0)
			(layer "B.SilkS")
			(hide yes)
			(effects
				(font
					(size 1.27 1.27)
				)
				(justify mirror)
			)
		)
		(property "Value" "DM-AMP-CONN200-13R-6-GP-01"
			(at 47.5488 -16.5862 180)
			(unlocked yes)
			(layer "B.Fab")
			(hide yes)
			(effects
				(font
					(size 1.016 1.016)
					(thickness 0.1524)
				)
				(justify mirror)
			)
		)
		(property "Device Type" "DMFIT-200P-384346H577-01"
			(at 47.5488 -18.1102 180)
			(unlocked yes)
			(layer "B.Fab")
			(hide yes)
			(effects
				(font
					(size 1.016 1.016)
					(thickness 0.1524)
				)
				(justify mirror)
			)
		)
		(duplicate_pad_numbers_are_jumpers no)
		(pad "" np_thru_hole circle
			(at 17.200118 -9.99998)
			(size 0.254 0.254)
			(drill 2.3876)
			(layers "*.Cu" "*.Mask")
			(clearance 1.4224)
			(thermal_gap 1.4224)
		)
		(pad "" np_thru_hole circle
			(at 17.200118 -2.469896)
			(size 0.254 0.254)
			(drill 2.4638)
			(layers "*.Cu" "*.Mask")
			(clearance 1.4605)
			(thermal_gap 1.4605)
		)
		(pad "A1" thru_hole circle
			(at 0 0)
			(size 0.762 0.762)
			(drill 0.359918)
			(layers "*.Cu" "*.Mask")
			(remove_unused_layers no)
			(net "PCIE_COMP_A_TO_IOM_A_CLK_2_DN")
			(clearance 0.1651)
			(thermal_gap 0.1651)
		)
		(pad "A2" thru_hole circle
			(at 1.800098 -0.999998)
			(size 0.762 0.762)
			(drill 0.359918)
			(layers "*.Cu" "*.Mask")
			(remove_unused_layers no)
			(net "I2C_BMC_A_MISC_SDA")
			(clearance 0.1651)
			(thermal_gap 0.1651)
		)
		(pad "A3" thru_hole circle
			(at 3.599942 0)
			(size 0.762 0.762)
			(drill 0.359918)
			(layers "*.Cu" "*.Mask")
			(remove_unused_layers no)
			(net "BMC_A_HEARTBEAT")
			(clearance 0.1651)
			(thermal_gap 0.1651)
		)
		(pad "A4" thru_hole circle
			(at 5.40004 -0.999998)
			(size 0.762 0.762)
			(drill 0.359918)
			(layers "*.Cu" "*.Mask")
			(remove_unused_layers no)
			(net "SCC_B_FULL_PWR_EN")
			(clearance 0.1651)
			(thermal_gap 0.1651)
		)
		(pad "A5" thru_hole circle
			(at 7.199884 0)
			(size 0.762 0.762)
			(drill 0.359918)
			(layers "*.Cu" "*.Mask")
			(remove_unused_layers no)
			(net "PCIE_COMP_A_TO_IOM_A_CLK_3_DN")
			(clearance 0.1651)
			(thermal_gap 0.1651)
		)
		(pad "A6" thru_hole circle
			(at 8.999982 -0.999998)
			(size 0.762 0.762)
			(drill 0.359918)
			(layers "*.Cu" "*.Mask")
			(remove_unused_layers no)
			(net "I2C_BMC_A_EXP_A_SDA")
			(clearance 0.1651)
			(thermal_gap 0.1651)
		)
		(pad "A7" thru_hole circle
			(at 10.80008 0)
			(size 0.762 0.762)
			(drill 0.359918)
			(layers "*.Cu" "*.Mask")
			(remove_unused_layers no)
			(net "P12V_A")
			(clearance 0.1651)
			(thermal_gap 0.1651)
		)
		(pad "A8" thru_hole circle
			(at 12.599924 -0.999998)
			(size 0.762 0.762)
			(drill 0.359918)
			(layers "*.Cu" "*.Mask")
			(remove_unused_layers no)
			(net "P12V_A")
			(clearance 0.1651)
			(thermal_gap 0.1651)
		)
		(pad "A9" thru_hole circle
			(at 21.599906 0)
			(size 0.762 0.762)
			(drill 0.359918)
			(layers "*.Cu" "*.Mask")
			(remove_unused_layers no)
			(net "PCIE_COMP_A_TO_IOM_A_CLK_4_DN")
			(clearance 0.1651)
			(thermal_gap 0.1651)
		)
		(pad "A10" thru_hole circle
			(at 23.400004 -0.999998)
			(size 0.762 0.762)
			(drill 0.359918)
			(layers "*.Cu" "*.Mask")
			(remove_unused_layers no)
			(net "IOM_A_SLOT_ID_1")
			(clearance 0.1651)
			(thermal_gap 0.1651)
		)
		(pad "A11" thru_hole circle
			(at 25.200102 0)
			(size 0.762 0.762)
			(drill 0.359918)
			(layers "*.Cu" "*.Mask")
			(remove_unused_layers no)
			(net "BMC_A_TO_EXP_A_RESET_N")
			(clearance 0.1651)
			(thermal_gap 0.1651)
		)
		(pad "A12" thru_hole circle
			(at 26.999946 -0.999998)
			(size 0.762 0.762)
			(drill 0.359918)
			(layers "*.Cu" "*.Mask")
			(remove_unused_layers no)
			(net "USB_COMP_A_DN")
			(clearance 0.1651)
			(thermal_gap 0.1651)
		)
		(pad "A13" thru_hole circle
			(at 28.800044 0)
			(size 0.762 0.762)
			(drill 0.359918)
			(layers "*.Cu" "*.Mask")
			(remove_unused_layers no)
			(net "COMP_A_TO_BMC_A_RESET_N")
			(clearance 0.1651)
			(thermal_gap 0.1651)
		)
		(pad "A14" thru_hole circle
			(at 30.599888 -0.999998)
			(size 0.762 0.762)
			(drill 0.359918)
			(layers "*.Cu" "*.Mask")
			(remove_unused_layers no)
			(net "I2C_DPB_A_SDA")
			(clearance 0.1651)
			(thermal_gap 0.1651)
		)
		(pad "A15" thru_hole circle
			(at 32.399986 0)
			(size 0.762 0.762)
			(drill 0.359918)
			(layers "*.Cu" "*.Mask")
			(remove_unused_layers no)
			(net "BMC_A_EXP_A_SPARE_1")
			(clearance 0.1651)
			(thermal_gap 0.1651)
		)
		(pad "A16" thru_hole circle
			(at 34.200084 -0.999998)
			(size 0.762 0.762)
			(drill 0.359918)
			(layers "*.Cu" "*.Mask")
			(remove_unused_layers no)
			(net "COMP_A_BMC_A_SPARE_1")
			(clearance 0.1651)
			(thermal_gap 0.1651)
		)
		(pad "B1" thru_hole circle
			(at 0 -1.400048)
			(size 0.762 0.762)
			(drill 0.359918)
			(layers "*.Cu" "*.Mask")
			(remove_unused_layers no)
			(net "PCIE_COMP_A_TO_IOM_A_CLK_2_DP")
			(clearance 0.1651)
			(thermal_gap 0.1651)
		)
		(pad "B2" thru_hole circle
			(at 1.800098 -2.400046)
			(size 0.762 0.762)
			(drill 0.359918)
			(layers "*.Cu" "*.Mask")
			(remove_unused_layers no)
			(net "I2C_BMC_A_MISC_SCL")
			(clearance 0.1651)
			(thermal_gap 0.1651)
		)
		(pad "B3" thru_hole circle
			(at 3.599942 -1.400048)
			(size 0.762 0.762)
			(drill 0.359918)
			(layers "*.Cu" "*.Mask")
			(remove_unused_layers no)
			(net "BMC_B_HEARTBEAT")
			(clearance 0.1651)
			(thermal_gap 0.1651)
		)
		(pad "B4" thru_hole circle
			(at 5.40004 -2.400046)
			(size 0.762 0.762)
			(drill 0.359918)
			(layers "*.Cu" "*.Mask")
			(remove_unused_layers no)
			(net "SCC_A_FULL_PWR_EN")
			(clearance 0.1651)
			(thermal_gap 0.1651)
		)
		(pad "B5" thru_hole circle
			(at 7.199884 -1.400048)
			(size 0.762 0.762)
			(drill 0.359918)
			(layers "*.Cu" "*.Mask")
			(remove_unused_layers no)
			(net "PCIE_COMP_A_TO_IOM_A_CLK_3_DP")
			(clearance 0.1651)
			(thermal_gap 0.1651)
		)
		(pad "B6" thru_hole circle
			(at 8.999982 -2.400046)
			(size 0.762 0.762)
			(drill 0.359918)
			(layers "*.Cu" "*.Mask")
			(remove_unused_layers no)
			(net "I2C_BMC_A_EXP_A_SCL")
			(clearance 0.1651)
			(thermal_gap 0.1651)
		)
		(pad "B7" thru_hole circle
			(at 10.80008 -1.400048)
			(size 0.762 0.762)
			(drill 0.359918)
			(layers "*.Cu" "*.Mask")
			(remove_unused_layers no)
			(net "P12V_A_PGOOD")
			(clearance 0.1651)
			(thermal_gap 0.1651)
		)
		(pad "B8" thru_hole circle
			(at 12.599924 -2.400046)
			(size 0.762 0.762)
			(drill 0.359918)
			(layers "*.Cu" "*.Mask")
			(remove_unused_layers no)
			(net "P12V_A")
			(clearance 0.1651)
			(thermal_gap 0.1651)
		)
		(pad "B9" thru_hole circle
			(at 21.599906 -1.400048)
			(size 0.762 0.762)
			(drill 0.359918)
			(layers "*.Cu" "*.Mask")
			(remove_unused_layers no)
			(net "PCIE_COMP_A_TO_IOM_A_CLK_4_DP")
			(clearance 0.1651)
			(thermal_gap 0.1651)
		)
		(pad "B10" thru_hole circle
			(at 23.400004 -2.400046)
			(size 0.762 0.762)
			(drill 0.359918)
			(layers "*.Cu" "*.Mask")
			(remove_unused_layers no)
			(net "IOM_A_SLOT_ID_0")
			(clearance 0.1651)
			(thermal_gap 0.1651)
		)
		(pad "B11" thru_hole circle
			(at 25.200102 -1.400048)
			(size 0.762 0.762)
			(drill 0.359918)
			(layers "*.Cu" "*.Mask")
			(remove_unused_layers no)
			(net "BMC_A_MISC_ALERT_N")
			(clearance 0.1651)
			(thermal_gap 0.1651)
		)
		(pad "B12" thru_hole circle
			(at 26.999946 -2.400046)
			(size 0.762 0.762)
			(drill 0.359918)
			(layers "*.Cu" "*.Mask")
			(remove_unused_layers no)
			(net "USB_COMP_A_DP")
			(clearance 0.1651)
			(thermal_gap 0.1651)
		)
		(pad "B13" thru_hole circle
			(at 28.800044 -1.400048)
			(size 0.762 0.762)
			(drill 0.359918)
			(layers "*.Cu" "*.Mask")
			(remove_unused_layers no)
			(net "SYS_A_RESET_N")
			(clearance 0.1651)
			(thermal_gap 0.1651)
		)
		(pad "B14" thru_hole circle
			(at 30.599888 -2.400046)
			(size 0.762 0.762)
			(drill 0.359918)
			(layers "*.Cu" "*.Mask")
			(remove_unused_layers no)
			(net "I2C_DPB_A_SCL")
			(clearance 0.1651)
			(thermal_gap 0.1651)
		)
		(pad "B15" thru_hole circle
			(at 32.399986 -1.400048)
			(size 0.762 0.762)
			(drill 0.359918)
			(layers "*.Cu" "*.Mask")
			(remove_unused_layers no)
			(net "BMC_A_EXP_A_SPARE_0")
			(clearance 0.1651)
			(thermal_gap 0.1651)
		)
		(pad "B16" thru_hole circle
			(at 34.200084 -2.400046)
			(size 0.762 0.762)
			(drill 0.359918)
			(layers "*.Cu" "*.Mask")
			(remove_unused_layers no)
			(net "COMP_A_BMC_A_SPARE_0")
			(clearance 0.1651)
			(thermal_gap 0.1651)
		)
		(pad "C1" thru_hole circle
			(at 0 -3.599942)
			(size 0.762 0.762)
			(drill 0.359918)
			(layers "*.Cu" "*.Mask")
			(remove_unused_layers no)
			(net "IOM_A_MATED_N")
			(clearance 0.1651)
			(thermal_gap 0.1651)
		)
		(pad "C2" thru_hole circle
			(at 1.800098 -4.59994)
			(size 0.762 0.762)
			(drill 0.359918)
			(layers "*.Cu" "*.Mask")
			(remove_unused_layers no)
			(net "I2C_SCC_A_SDA")
			(clearance 0.1651)
			(thermal_gap 0.1651)
		)
		(pad "C3" thru_hole circle
			(at 3.599942 -3.599942)
			(size 0.762 0.762)
			(drill 0.359918)
			(layers "*.Cu" "*.Mask")
			(remove_unused_layers no)
			(net "SCC_B_HEARTBEAT")
			(clearance 0.1651)
			(thermal_gap 0.1651)
		)
		(pad "C4" thru_hole circle
			(at 5.40004 -4.59994)
			(size 0.762 0.762)
			(drill 0.359918)
			(layers "*.Cu" "*.Mask")
			(remove_unused_layers no)
			(net "IOM_A_PWR_LED")
			(clearance 0.1651)
			(thermal_gap 0.1651)
		)
		(pad "C5" thru_hole circle
			(at 7.199884 -3.599942)
			(size 0.762 0.762)
			(drill 0.359918)
			(layers "*.Cu" "*.Mask")
			(remove_unused_layers no)
			(net "IOM_A_INS_N")
			(clearance 0.1651)
			(thermal_gap 0.1651)
		)
		(pad "C6" thru_hole circle
			(at 8.999982 -4.59994)
			(size 0.762 0.762)
			(drill 0.359918)
			(layers "*.Cu" "*.Mask")
			(remove_unused_layers no)
			(net "I2C_BMC_A_EXP_B_SDA")
			(clearance 0.1651)
			(thermal_gap 0.1651)
		)
		(pad "C7" thru_hole circle
			(at 10.80008 -3.599942)
			(size 0.762 0.762)
			(drill 0.359918)
			(layers "*.Cu" "*.Mask")
			(remove_unused_layers no)
			(net "UART_SDB_A_RX")
			(clearance 0.1651)
			(thermal_gap 0.1651)
		)
		(pad "C8" thru_hole circle
			(at 12.599924 -4.59994)
			(size 0.762 0.762)
			(drill 0.359918)
			(layers "*.Cu" "*.Mask")
			(remove_unused_layers no)
			(net "P12V_A")
			(clearance 0.1651)
			(thermal_gap 0.1651)
		)
		(pad "C9" thru_hole circle
			(at 21.599906 -3.599942)
			(size 0.762 0.762)
			(drill 0.359918)
			(layers "*.Cu" "*.Mask")
			(remove_unused_layers no)
			(net "COMP_A_BMC_A_ALERT_N")
			(clearance 0.1651)
			(thermal_gap 0.1651)
		)
		(pad "C10" thru_hole circle
			(at 23.400004 -4.59994)
			(size 0.762 0.762)
			(drill 0.359918)
			(layers "*.Cu" "*.Mask")
			(remove_unused_layers no)
			(net "I2C_BMC_A_COMP_A_SDA_BUF")
			(clearance 0.1651)
			(thermal_gap 0.1651)
		)
		(pad "C11" thru_hole circle
			(at 25.200102 -3.599942)
			(size 0.762 0.762)
			(drill 0.359918)
			(layers "*.Cu" "*.Mask")
			(remove_unused_layers no)
			(net "UART_COMP_A_RX")
			(clearance 0.1651)
			(thermal_gap 0.1651)
		)
		(pad "C12" thru_hole circle
			(at 26.999946 -4.59994)
			(size 0.762 0.762)
			(drill 0.359918)
			(layers "*.Cu" "*.Mask")
			(remove_unused_layers no)
			(net "COMP_A_PWR_EN")
			(clearance 0.1651)
			(thermal_gap 0.1651)
		)
		(pad "C13" thru_hole circle
			(at 28.800044 -3.599942)
			(size 0.762 0.762)
			(drill 0.359918)
			(layers "*.Cu" "*.Mask")
			(remove_unused_layers no)
			(net "COMP_A_POWER_FAIL_N")
			(clearance 0.1651)
			(thermal_gap 0.1651)
		)
		(pad "C14" thru_hole circle
			(at 30.599888 -4.59994)
			(size 0.762 0.762)
			(drill 0.359918)
			(layers "*.Cu" "*.Mask")
			(remove_unused_layers no)
			(net "Net_18")
			(clearance 0.1651)
			(thermal_gap 0.1651)
		)
		(pad "C15" thru_hole circle
			(at 32.399986 -3.599942)
			(size 0.762 0.762)
			(drill 0.359918)
			(layers "*.Cu" "*.Mask")
			(remove_unused_layers no)
			(net "Net_19")
			(clearance 0.1651)
			(thermal_gap 0.1651)
		)
		(pad "C16" thru_hole circle
			(at 34.200084 -4.59994)
			(size 0.762 0.762)
			(drill 0.359918)
			(layers "*.Cu" "*.Mask")
			(remove_unused_layers no)
			(net "PWM_BMC_A_ZONE_C")
			(clearance 0.1651)
			(thermal_gap 0.1651)
		)
		(pad "D1" thru_hole circle
			(at 0 -4.99999)
			(size 0.762 0.762)
			(drill 0.359918)
			(layers "*.Cu" "*.Mask")
			(remove_unused_layers no)
			(net "PCIE_COMP_A_TO_IOM_A_RST_2")
			(clearance 0.1651)
			(thermal_gap 0.1651)
		)
		(pad "D2" thru_hole circle
			(at 1.800098 -5.999988)
			(size 0.762 0.762)
			(drill 0.359918)
			(layers "*.Cu" "*.Mask")
			(remove_unused_layers no)
			(net "I2C_SCC_A_SCL")
			(clearance 0.1651)
			(thermal_gap 0.1651)
		)
		(pad "D3" thru_hole circle
			(at 3.599942 -4.99999)
			(size 0.762 0.762)
			(drill 0.359918)
			(layers "*.Cu" "*.Mask")
			(remove_unused_layers no)
			(net "SCC_A_HEARTBEAT")
			(clearance 0.1651)
			(thermal_gap 0.1651)
		)
		(pad "D4" thru_hole circle
			(at 5.40004 -5.999988)
			(size 0.762 0.762)
			(drill 0.359918)
			(layers "*.Cu" "*.Mask")
			(remove_unused_layers no)
			(net "SCC_A_STBY_PWR_EN")
			(clearance 0.1651)
			(thermal_gap 0.1651)
		)
		(pad "D5" thru_hole circle
			(at 7.199884 -4.99999)
			(size 0.762 0.762)
			(drill 0.359918)
			(layers "*.Cu" "*.Mask")
			(remove_unused_layers no)
			(net "PCIE_COMP_A_TO_IOM_A_RST_3")
			(clearance 0.1651)
			(thermal_gap 0.1651)
		)
		(pad "D6" thru_hole circle
			(at 8.999982 -5.999988)
			(size 0.762 0.762)
			(drill 0.359918)
			(layers "*.Cu" "*.Mask")
			(remove_unused_layers no)
			(net "I2C_BMC_A_EXP_B_SCL")
			(clearance 0.1651)
			(thermal_gap 0.1651)
		)
		(pad "D7" thru_hole circle
			(at 10.80008 -4.99999)
			(size 0.762 0.762)
			(drill 0.359918)
			(layers "*.Cu" "*.Mask")
			(remove_unused_layers no)
			(net "UART_SDB_A_TX")
			(clearance 0.1651)
			(thermal_gap 0.1651)
		)
		(pad "D8" thru_hole circle
			(at 12.599924 -5.999988)
			(size 0.762 0.762)
			(drill 0.359918)
			(layers "*.Cu" "*.Mask")
			(remove_unused_layers no)
			(net "P12V_A")
			(clearance 0.1651)
			(thermal_gap 0.1651)
		)
		(pad "D9" thru_hole circle
			(at 21.599906 -4.99999)
			(size 0.762 0.762)
			(drill 0.359918)
			(layers "*.Cu" "*.Mask")
			(remove_unused_layers no)
			(net "PCIE_COMP_A_TO_IOM_A_RST_4")
			(clearance 0.1651)
			(thermal_gap 0.1651)
		)
		(pad "D10" thru_hole circle
			(at 23.400004 -5.999988)
			(size 0.762 0.762)
			(drill 0.359918)
			(layers "*.Cu" "*.Mask")
			(remove_unused_layers no)
			(net "I2C_BMC_A_COMP_A_SCL_BUF")
			(clearance 0.1651)
			(thermal_gap 0.1651)
		)
		(pad "D11" thru_hole circle
			(at 25.200102 -4.99999)
			(size 0.762 0.762)
			(drill 0.359918)
			(layers "*.Cu" "*.Mask")
			(remove_unused_layers no)
			(net "UART_COMP_A_TX")
			(clearance 0.1651)
			(thermal_gap 0.1651)
		)
		(pad "D12" thru_hole circle
			(at 26.999946 -5.999988)
			(size 0.762 0.762)
			(drill 0.359918)
			(layers "*.Cu" "*.Mask")
			(remove_unused_layers no)
			(net "SCC_B_TYPE_0")
			(clearance 0.1651)
			(thermal_gap 0.1651)
		)
		(pad "D13" thru_hole circle
			(at 28.800044 -4.99999)
			(size 0.762 0.762)
			(drill 0.359918)
			(layers "*.Cu" "*.Mask")
			(remove_unused_layers no)
			(net "COMP_A_FAST_THROTTLE_N")
			(clearance 0.1651)
			(thermal_gap 0.1651)
		)
		(pad "D14" thru_hole circle
			(at 30.599888 -5.999988)
			(size 0.762 0.762)
			(drill 0.359918)
			(layers "*.Cu" "*.Mask")
			(remove_unused_layers no)
			(net "COMP_A_PWR_BTN_N")
			(clearance 0.1651)
			(thermal_gap 0.1651)
		)
		(pad "D15" thru_hole circle
			(at 32.399986 -4.99999)
			(size 0.762 0.762)
			(drill 0.359918)
			(layers "*.Cu" "*.Mask")
			(remove_unused_layers no)
			(net "IOM_A_FAULT_LED")
			(clearance 0.1651)
			(thermal_gap 0.1651)
		)
		(pad "D16" thru_hole circle
			(at 34.200084 -5.999988)
			(size 0.762 0.762)
			(drill 0.359918)
			(layers "*.Cu" "*.Mask")
			(remove_unused_layers no)
			(net "PWM_BMC_A_ZONE_D")
			(clearance 0.1651)
			(thermal_gap 0.1651)
		)
		(pad "E1" thru_hole circle
			(at 0 -7.199884)
			(size 0.664718 0.664718)
			(drill 0.359918)
			(layers "*.Cu" "*.Mask")
			(remove_unused_layers no)
			(net "PCIE_IOM_A_TO_COMP_A_8_DN")
			(clearance 0.264414)
			(padstack
				(mode custom)
				(layer "In1.Cu"
					(shape circle)
					(size 0.664718 0.664718)
					(clearance 0.264414)
				)
				(layer "In2.Cu"
					(shape circle)
					(size 0.664718 0.664718)
					(clearance 0.264414)
				)
				(layer "In3.Cu"
					(shape circle)
					(size 0.664718 0.664718)
					(clearance 0.264414)
				)
				(layer "In4.Cu"
					(shape circle)
					(size 0.664718 0.664718)
					(clearance 0.264414)
				)
				(layer "In5.Cu"
					(shape circle)
					(size 0.664718 0.664718)
					(clearance 0.264414)
				)
				(layer "In6.Cu"
					(shape circle)
					(size 0.762 0.762)
					(clearance 0.1651)
				)
				(layer "In7.Cu"
					(shape circle)
					(size 0.762 0.762)
					(clearance 0.1651)
				)
				(layer "In8.Cu"
					(shape circle)
					(size 0.762 0.762)
					(clearance 0.1651)
				)
				(layer "In9.Cu"
					(shape circle)
					(size 0.762 0.762)
					(clearance 0.1651)
				)
				(layer "In10.Cu"
					(shape circle)
					(size 0.762 0.762)
					(clearance 0.1651)
				)
				(layer "B.Cu"
					(shape circle)
					(size 0.762 0.762)
					(thermal_gap 0.1651)
					(clearance 0.1651)
				)
			)
		)
	)
)
